(kicad_pcb
	(version 20260206)
	(generator "pcbnew")
	(generator_version "10.0")
	(general
		(thickness 1.6)
		(legacy_teardrops no)
	)
	(paper "A4")
	(title_block
		(title "Wiwynn_Tioga_Pass_MB.brd")
		(comment 1 "Tioga Pass / footprints 3278-3282 of 4770")
	)
	(layers
		(0 "F.Cu" signal "TOP")
		(4 "In1.Cu" signal "L2GND")
		(6 "In2.Cu" signal "L3")
		(8 "In3.Cu" signal "L4GND")
		(10 "In4.Cu" signal "L5")
		(12 "In5.Cu" signal "L6GND")
		(14 "In6.Cu" signal "L7VCC")
		(16 "In7.Cu" signal "L8VCC")
		(18 "In8.Cu" signal "L9GND")
		(20 "In9.Cu" signal "L10")
		(22 "In10.Cu" signal "L11GND")
		(24 "In11.Cu" signal "L12")
		(26 "In12.Cu" signal "L13GND")
		(2 "B.Cu" signal "BOTTOM")
		(9 "F.Adhes" user "F.Adhesive")
		(11 "B.Adhes" user "B.Adhesive")
		(13 "F.Paste" user "Package Geometry/Pastemask Top")
		(15 "B.Paste" user "Package Geometry/Pastemask Bottom")
		(5 "F.SilkS" user "Ref Des/Silkscreen Top")
		(7 "B.SilkS" user "Ref Des/Silkscreen Bottom")
		(1 "F.Mask" user "Board Geometry/Soldermask Top")
		(3 "B.Mask" user "Board Geometry/Soldermask Bottom")
		(17 "Dwgs.User" user "User.Drawings")
		(19 "Cmts.User" user "User.Comments")
		(21 "Eco1.User" user "User.Eco1")
		(23 "Eco2.User" user "User.Eco2")
		(25 "Edge.Cuts" user "Board Geometry/Outline")
		(27 "Margin" user)
		(31 "F.CrtYd" user "Package Geometry/Place Bound Top")
		(29 "B.CrtYd" user "Package Geometry/Place Bound Bottom")
		(35 "F.Fab" user "Ref Des/Assembly Top")
		(33 "B.Fab" user "Ref Des/Assembly Bottom")
	)
	(footprint ""
		(layer "B.Cu")
		(at 271.350486 -77.82814)
		(property "Reference" "C5P20"
			(at 0 0 0)
			(layer "B.SilkS")
			(hide yes)
			(effects
				(font
					(size 1.27 1.27)
				)
				(justify mirror)
			)
		)
		(property "Value" ""
			(at 0 0 0)
			(layer "B.Fab")
			(effects
				(font
					(size 1.27 1.27)
				)
				(justify mirror)
			)
		)
		(duplicate_pad_numbers_are_jumpers no)
		(fp_poly
			(pts
				(xy 0.7239 -0.2159) (xy -0.7239 -0.2159) (xy -0.7239 1.9939) (xy 0.7239 1.9939)
			)
			(stroke
				(width 0)
				(type default)
			)
			(fill no)
			(layer "B.CrtYd")
		)
		(fp_line
			(start -0.7239 -0.2159)
			(end 0.7239 -0.2159)
			(stroke
				(width 0.1)
				(type default)
			)
			(layer "B.Fab")
		)
		(fp_line
			(start -0.7239 1.9939)
			(end -0.7239 -0.2159)
			(stroke
				(width 0.1)
				(type default)
			)
			(layer "B.Fab")
		)
		(fp_line
			(start 0.7239 -0.2159)
			(end 0.7239 1.9939)
			(stroke
				(width 0.1)
				(type default)
			)
			(layer "B.Fab")
		)
		(fp_line
			(start 0.7239 1.9939)
			(end -0.7239 1.9939)
			(stroke
				(width 0.1)
				(type default)
			)
			(layer "B.Fab")
		)
		(pad "1" smd rect
			(at 0 0 180)
			(size 1.27 1.016)
			(layers "B.Cu" "B.Mask" "B.Paste")
			(net "PVCCMCP_CPU0")
		)
		(pad "2" smd rect
			(at 0 1.778 180)
			(size 1.27 1.016)
			(layers "B.Cu" "B.Mask" "B.Paste")
			(net "GND")
		)
		(zone
			(layer "B.Cu")
			(hatch none 0.5)
			(connect_pads
				(clearance 0)
			)
			(min_thickness 0.25)
			(keepout
				(tracks not_allowed)
				(vias allowed)
				(pads allowed)
				(copperpour not_allowed)
				(footprints allowed)
			)
			(placement
				(enabled no)
				(sheetname "")
			)
			(fill
				(thermal_gap 0.5)
				(thermal_bridge_width 0.5)
				(island_removal_mode 0)
			)
			(polygon
				(pts
					(xy 271.985486 -77.32014) (xy 270.715486 -77.32014) (xy 270.715486 -76.55814) (xy 271.985486 -76.55814)
				)
			)
		)
	)
	(footprint ""
		(layer "B.Cu")
		(at 351.13468 -89.067132 90)
		(property "Reference" "C4W1"
			(at 0.8382 -0.67818 90)
			(unlocked yes)
			(layer "B.SilkS")
			(effects
				(font
					(size 0.4064 0.254)
					(thickness 0.1524)
				)
				(justify left mirror)
			)
		)
		(property "Value" ""
			(at 0 0 90)
			(layer "B.Fab")
			(effects
				(font
					(size 1.27 1.27)
				)
				(justify mirror)
			)
		)
		(duplicate_pad_numbers_are_jumpers no)
		(fp_poly
			(pts
				(xy -0.3048 -0.1016) (xy -0.3048 0.9906) (xy 0.3048 0.9906) (xy 0.3048 -0.1016)
			)
			(stroke
				(width 0)
				(type default)
			)
			(fill no)
			(layer "B.CrtYd")
		)
		(fp_line
			(start 0.3048 -0.1016)
			(end 0.3048 0.9906)
			(stroke
				(width 0.1)
				(type default)
			)
			(layer "B.Fab")
		)
		(fp_line
			(start -0.3048 -0.1016)
			(end 0.3048 -0.1016)
			(stroke
				(width 0.1)
				(type default)
			)
			(layer "B.Fab")
		)
		(fp_line
			(start 0.3048 0.9906)
			(end -0.3048 0.9906)
			(stroke
				(width 0.1)
				(type default)
			)
			(layer "B.Fab")
		)
		(fp_line
			(start -0.3048 0.9906)
			(end -0.3048 -0.1016)
			(stroke
				(width 0.1)
				(type default)
			)
			(layer "B.Fab")
		)
		(pad "1" smd rect
			(at 0 0 270)
			(size 0.508 0.508)
			(layers "B.Cu" "B.Mask" "B.Paste")
			(net "A_TSENSE_PVCCIO_CPU0")
		)
		(pad "2" smd rect
			(at 0 0.889 270)
			(size 0.508 0.508)
			(layers "B.Cu" "B.Mask" "B.Paste")
			(net "GND")
		)
		(zone
			(layer "B.Cu")
			(hatch none 0.5)
			(connect_pads
				(clearance 0)
			)
			(min_thickness 0.25)
			(keepout
				(tracks allowed)
				(vias not_allowed)
				(pads allowed)
				(copperpour not_allowed)
				(footprints allowed)
			)
			(placement
				(enabled no)
				(sheetname "")
			)
			(fill
				(thermal_gap 0.5)
				(thermal_bridge_width 0.5)
				(island_removal_mode 0)
			)
			(polygon
				(pts
					(xy 351.38868 -89.321132) (xy 351.38868 -88.813132) (xy 351.76968 -88.813132) (xy 351.76968 -89.321132)
				)
			)
		)
		(zone
			(layer "B.Cu")
			(hatch none 0.5)
			(connect_pads
				(clearance 0)
			)
			(min_thickness 0.25)
			(keepout
				(tracks not_allowed)
				(vias allowed)
				(pads allowed)
				(copperpour not_allowed)
				(footprints allowed)
			)
			(placement
				(enabled no)
				(sheetname "")
			)
			(fill
				(thermal_gap 0.5)
				(thermal_bridge_width 0.5)
				(island_removal_mode 0)
			)
			(polygon
				(pts
					(xy 351.76968 -89.321132) (xy 351.76968 -88.813132) (xy 351.38868 -88.813132) (xy 351.38868 -89.321132)
				)
			)
		)
	)
	(footprint ""
		(layer "B.Cu")
		(at 385.34594 -30.571694 90)
		(property "Reference" "C2T10"
			(at 0 0 90)
			(layer "B.SilkS")
			(hide yes)
			(effects
				(font
					(size 1.27 1.27)
				)
				(justify mirror)
			)
		)
		(property "Value" ""
			(at 0 0 90)
			(layer "B.Fab")
			(effects
				(font
					(size 1.27 1.27)
				)
				(justify mirror)
			)
		)
		(duplicate_pad_numbers_are_jumpers no)
		(fp_poly
			(pts
				(xy -0.3048 -0.1016) (xy -0.3048 0.9906) (xy 0.3048 0.9906) (xy 0.3048 -0.1016)
			)
			(stroke
				(width 0)
				(type default)
			)
			(fill no)
			(layer "B.CrtYd")
		)
		(fp_line
			(start 0.3048 -0.1016)
			(end 0.3048 0.9906)
			(stroke
				(width 0.1)
				(type default)
			)
			(layer "B.Fab")
		)
		(fp_line
			(start -0.3048 -0.1016)
			(end 0.3048 -0.1016)
			(stroke
				(width 0.1)
				(type default)
			)
			(layer "B.Fab")
		)
		(fp_line
			(start 0.3048 0.9906)
			(end -0.3048 0.9906)
			(stroke
				(width 0.1)
				(type default)
			)
			(layer "B.Fab")
		)
		(fp_line
			(start -0.3048 0.9906)
			(end -0.3048 -0.1016)
			(stroke
				(width 0.1)
				(type default)
			)
			(layer "B.Fab")
		)
		(pad "1" smd rect
			(at 0 0 270)
			(size 0.508 0.508)
			(layers "B.Cu" "B.Mask" "B.Paste")
			(net "P3E_PCH_M2_TX_C_DP<1>")
		)
		(pad "2" smd rect
			(at 0 0.889 270)
			(size 0.508 0.508)
			(layers "B.Cu" "B.Mask" "B.Paste")
			(net "P3E_PCH_M2_TX_DP<1>")
		)
		(zone
			(layer "B.Cu")
			(hatch none 0.5)
			(connect_pads
				(clearance 0)
			)
			(min_thickness 0.25)
			(keepout
				(tracks allowed)
				(vias not_allowed)
				(pads allowed)
				(copperpour not_allowed)
				(footprints allowed)
			)
			(placement
				(enabled no)
				(sheetname "")
			)
			(fill
				(thermal_gap 0.5)
				(thermal_bridge_width 0.5)
				(island_removal_mode 0)
			)
			(polygon
				(pts
					(xy 385.59994 -30.825694) (xy 385.59994 -30.317694) (xy 385.98094 -30.317694) (xy 385.98094 -30.825694)
				)
			)
		)
		(zone
			(layer "B.Cu")
			(hatch none 0.5)
			(connect_pads
				(clearance 0)
			)
			(min_thickness 0.25)
			(keepout
				(tracks not_allowed)
				(vias allowed)
				(pads allowed)
				(copperpour not_allowed)
				(footprints allowed)
			)
			(placement
				(enabled no)
				(sheetname "")
			)
			(fill
				(thermal_gap 0.5)
				(thermal_bridge_width 0.5)
				(island_removal_mode 0)
			)
			(polygon
				(pts
					(xy 385.98094 -30.825694) (xy 385.98094 -30.317694) (xy 385.59994 -30.317694) (xy 385.59994 -30.825694)
				)
			)
		)
	)
	(footprint ""
		(layer "B.Cu")
		(at 347.316806 -60.368434)
		(property "Reference" "R2U24"
			(at 0 0 0)
			(layer "B.SilkS")
			(hide yes)
			(effects
				(font
					(size 1.27 1.27)
				)
				(justify mirror)
			)
		)
		(property "Value" ""
			(at 0 0 0)
			(layer "B.Fab")
			(effects
				(font
					(size 1.27 1.27)
				)
				(justify mirror)
			)
		)
		(duplicate_pad_numbers_are_jumpers no)
		(fp_poly
			(pts
				(xy 0.2794 -0.1016) (xy -0.2794 -0.1016) (xy -0.2794 0.9906) (xy 0.2794 0.9906)
			)
			(stroke
				(width 0)
				(type default)
			)
			(fill no)
			(layer "B.CrtYd")
		)
		(fp_line
			(start -0.2794 -0.1016)
			(end 0.2794 -0.1016)
			(stroke
				(width 0.1)
				(type default)
			)
			(layer "B.Fab")
		)
		(fp_line
			(start -0.2794 0.9906)
			(end -0.2794 -0.1016)
			(stroke
				(width 0.1)
				(type default)
			)
			(layer "B.Fab")
		)
		(fp_line
			(start 0.2794 -0.1016)
			(end 0.2794 0.9906)
			(stroke
				(width 0.1)
				(type default)
			)
			(layer "B.Fab")
		)
		(fp_line
			(start 0.2794 0.9906)
			(end -0.2794 0.9906)
			(stroke
				(width 0.1)
				(type default)
			)
			(layer "B.Fab")
		)
		(pad "1" smd rect
			(at 0 0 180)
			(size 0.508 0.508)
			(layers "B.Cu" "B.Mask" "B.Paste")
			(net "P3E_CPU0_PE1_SS_RXP<5>")
		)
		(pad "2" smd rect
			(at 0 0.889 180)
			(size 0.508 0.508)
			(layers "B.Cu" "B.Mask" "B.Paste")
			(net "P3E_CPU0_PE1_SS_R_RXP<5>")
		)
		(zone
			(layer "B.Cu")
			(hatch none 0.5)
			(connect_pads
				(clearance 0)
			)
			(min_thickness 0.25)
			(keepout
				(tracks allowed)
				(vias not_allowed)
				(pads allowed)
				(copperpour not_allowed)
				(footprints allowed)
			)
			(placement
				(enabled no)
				(sheetname "")
			)
			(fill
				(thermal_gap 0.5)
				(thermal_bridge_width 0.5)
				(island_removal_mode 0)
			)
			(polygon
				(pts
					(xy 347.570806 -60.114434) (xy 347.062806 -60.114434) (xy 347.062806 -59.733434) (xy 347.570806 -59.733434)
				)
			)
		)
	)
	(footprint ""
		(layer "B.Cu")
		(at 153.794968 -154.782012 -90)
		(property "Reference" "C7L3"
			(at 0 0 90)
			(layer "B.SilkS")
			(hide yes)
			(effects
				(font
					(size 1.27 1.27)
				)
				(justify mirror)
			)
		)
		(property "Value" ""
			(at 0 0 90)
			(layer "B.Fab")
			(effects
				(font
					(size 1.27 1.27)
				)
				(justify mirror)
			)
		)
		(duplicate_pad_numbers_are_jumpers no)
		(fp_rect
			(start 0.4953 1.6002)
			(end -0.4953 -0.2032)
			(stroke
				(width 0)
				(type default)
			)
			(fill no)
			(layer "B.CrtYd")
		)
		(fp_line
			(start -0.4953 1.6002)
			(end 0.4953 1.6002)
			(stroke
				(width 0.1)
				(type default)
			)
			(layer "B.Fab")
		)
		(fp_line
			(start 0.4953 1.6002)
			(end 0.4953 -0.2032)
			(stroke
				(width 0.1)
				(type default)
			)
			(layer "B.Fab")
		)
		(fp_line
			(start -0.4953 -0.2032)
			(end -0.4953 1.6002)
			(stroke
				(width 0.1)
				(type default)
			)
			(layer "B.Fab")
		)
		(fp_line
			(start 0.4953 -0.2032)
			(end -0.4953 -0.2032)
			(stroke
				(width 0.1)
				(type default)
			)
			(layer "B.Fab")
		)
		(pad "1" smd rect
			(at 0 0 90)
			(size 0.762 0.889)
			(layers "B.Cu" "B.Mask" "B.Paste")
			(net "PVPP_KLM")
		)
		(pad "2" smd rect
			(at 0 1.397 90)
			(size 0.762 0.889)
			(layers "B.Cu" "B.Mask" "B.Paste")
			(net "GND")
		)
		(zone
			(layer "B.Cu")
			(hatch none 0.5)
			(connect_pads
				(clearance 0)
			)
			(min_thickness 0.25)
			(keepout
				(tracks not_allowed)
				(vias allowed)
				(pads allowed)
				(copperpour not_allowed)
				(footprints allowed)
			)
			(placement
				(enabled no)
				(sheetname "")
			)
			(fill
				(thermal_gap 0.5)
				(thermal_bridge_width 0.5)
				(island_removal_mode 0)
			)
			(polygon
				(pts
					(xy 152.842468 -154.401012) (xy 153.350468 -154.401012) (xy 153.350468 -155.163012) (xy 152.842468 -155.163012)
				)
			)
		)
	)
)
